# m2-pcie-adapter — KiCad project settings (.kicad_pro: net classes, design rules, text variables)
{
  "board": {
    "3dviewports": [],
    "design_settings": {
      "defaults": {
        "apply_defaults_to_fp_fields": false,
        "apply_defaults_to_fp_shapes": false,
        "apply_defaults_to_fp_text": false,
        "board_outline_line_width": 0.15,
        "copper_line_width": 1.5,
        "copper_text_italic": false,
        "copper_text_size_h": 1.5,
        "copper_text_size_v": 1.5,
        "copper_text_thickness": 0.3,
        "copper_text_upright": true,
        "courtyard_line_width": 0.05,
        "dimension_precision": 4,
        "dimension_units": 3,
        "dimensions": {
          "arrow_length": 1270000,
          "extension_offset": 500000,
          "keep_text_aligned": true,
          "suppress_zeroes": false,
          "text_position": 0,
          "units_format": 1
        },
        "fab_line_width": 0.1,
        "fab_text_italic": false,
        "fab_text_size_h": 1.0,
        "fab_text_size_v": 1.0,
        "fab_text_thickness": 0.15,
        "fab_text_upright": false,
        "other_line_width": 0.15,
        "other_text_italic": false,
        "other_text_size_h": 1.0,
        "other_text_size_v": 1.0,
        "other_text_thickness": 0.15,
        "other_text_upright": true,
        "pads": {
          "drill": 0.0,
          "height": 2.2,
          "width": 0.35
        },
        "silk_line_width": 0.15,
        "silk_text_italic": false,
        "silk_text_size_h": 0.6,
        "silk_text_size_v": 0.6,
        "silk_text_thickness": 0.15,
        "silk_text_upright": true,
        "zones": {
          "min_clearance": 0.3
        }
      },
      "diff_pair_dimensions": [
        {
          "gap": 0.0,
          "via_gap": 0.0,
          "width": 0.0
        }
      ],
      "drc_exclusions": [],
      "meta": {
        "version": 2
      },
      "rule_severities": {
        "annular_width": "error",
        "clearance": "error",
        "connection_width": "warning",
        "copper_edge_clearance": "error",
        "copper_sliver": "warning",
        "courtyards_overlap": "error",
        "creepage": "error",
        "diff_pair_gap_out_of_range": "error",
        "diff_pair_uncoupled_length_too_long": "error",
        "drill_out_of_range": "error",
        "duplicate_footprints": "warning",
        "extra_footprint": "warning",
        "footprint": "error",
        "footprint_filters_mismatch": "ignore",
        "footprint_symbol_mismatch": "warning",
        "footprint_type_mismatch": "ignore",
        "hole_clearance": "error",
        "hole_near_hole": "error",
        "hole_to_hole": "error",
        "holes_co_located": "warning",
        "invalid_outline": "error",
        "isolated_copper": "warning",
        "item_on_disabled_layer": "error",
        "items_not_allowed": "error",
        "length_out_of_range": "error",
        "lib_footprint_issues": "warning",
        "lib_footprint_mismatch": "warning",
        "malformed_courtyard": "error",
        "microvia_drill_out_of_range": "error",
        "mirrored_text_on_front_layer": "warning",
        "missing_courtyard": "ignore",
        "missing_footprint": "warning",
        "net_conflict": "warning",
        "nonmirrored_text_on_back_layer": "warning",
        "npth_inside_courtyard": "ignore",
        "padstack": "warning",
        "pth_inside_courtyard": "ignore",
        "shorting_items": "error",
        "silk_edge_clearance": "warning",
        "silk_over_copper": "warning",
        "silk_overlap": "warning",
        "skew_out_of_range": "error",
        "solder_mask_bridge": "error",
        "starved_thermal": "error",
        "text_height": "warning",
        "text_on_edge_cuts": "error",
        "text_thickness": "warning",
        "through_hole_pad_without_hole": "error",
        "too_many_vias": "error",
        "track_angle": "error",
        "track_dangling": "warning",
        "track_segment_length": "error",
        "track_width": "error",
        "tracks_crossing": "error",
        "unconnected_items": "error",
        "unresolved_variable": "error",
        "via_dangling": "warning",
        "zones_intersect": "error"
      },
      "rule_severitieslegacy_courtyards_overlap": true,
      "rule_severitieslegacy_no_courtyard_defined": false,
      "rules": {
        "allow_blind_buried_vias": false,
        "allow_microvias": false,
        "max_error": 0.005,
        "min_clearance": 0.0,
        "min_connection": 0.0,
        "min_copper_edge_clearance": 0.2,
        "min_groove_width": 0.0,
        "min_hole_clearance": 0.25,
        "min_hole_to_hole": 0.25,
        "min_microvia_diameter": 0.2,
        "min_microvia_drill": 0.1,
        "min_resolved_spokes": 1,
        "min_silk_clearance": 0.0,
        "min_text_height": 0.7,
        "min_text_thickness": 0.08,
        "min_through_hole_diameter": 0.25,
        "min_track_width": 0.18,
        "min_via_annular_width": 0.1,
        "min_via_diameter": 0.4,
        "solder_mask_clearance": 0.051,
        "solder_mask_min_width": 0.25,
        "solder_mask_to_copper_clearance": 0.0,
        "solder_paste_clearance": 0.0,
        "solder_paste_margin_ratio": -0.0,
        "use_height_for_length_calcs": true
      },
      "teardrop_options": [
        {
          "td_onpthpad": true,
          "td_onroundshapesonly": false,
          "td_onsmdpad": true,
          "td_ontrackend": false,
          "td_onvia": true
        }
      ],
      "teardrop_parameters": [
        {
          "td_allow_use_two_tracks": true,
          "td_curve_segcount": 1,
          "td_height_ratio": 1.0,
          "td_length_ratio": 0.5,
          "td_maxheight": 2.0,
          "td_maxlen": 1.0,
          "td_on_pad_in_zone": false,
          "td_target_name": "td_round_shape",
          "td_width_to_size_filter_ratio": 0.9
        },
        {
          "td_allow_use_two_tracks": true,
          "td_curve_segcount": 1,
          "td_height_ratio": 1.0,
          "td_length_ratio": 0.5,
          "td_maxheight": 2.0,
          "td_maxlen": 1.0,
          "td_on_pad_in_zone": false,
          "td_target_name": "td_rect_shape",
          "td_width_to_size_filter_ratio": 0.9
        },
        {
          "td_allow_use_two_tracks": true,
          "td_curve_segcount": 1,
          "td_height_ratio": 1.0,
          "td_length_ratio": 0.5,
          "td_maxheight": 2.0,
          "td_maxlen": 1.0,
          "td_on_pad_in_zone": false,
          "td_target_name": "td_track_end",
          "td_width_to_size_filter_ratio": 0.9
        }
      ],
      "track_widths": [
        0.0,
        0.5,
        1.0,
        1.5
      ],
      "tuning_pattern_settings": {
        "diff_pair_defaults": {
          "corner_radius_percentage": 80,
          "corner_style": 1,
          "max_amplitude": 1.0,
          "min_amplitude": 0.2,
          "single_sided": false,
          "spacing": 1.0
        },
        "diff_pair_skew_defaults": {
          "corner_radius_percentage": 80,
          "corner_style": 1,
          "max_amplitude": 1.0,
          "min_amplitude": 0.2,
          "single_sided": false,
          "spacing": 0.6
        },
        "single_track_defaults": {
          "corner_radius_percentage": 80,
          "corner_style": 1,
          "max_amplitude": 1.0,
          "min_amplitude": 0.2,
          "single_sided": false,
          "spacing": 0.6
        }
      },
      "via_dimensions": [
        {
          "diameter": 0.0,
          "drill": 0.0
        }
      ],
      "zones_allow_external_fillets": false
    },
    "ipc2581": {
      "dist": "",
      "distpn": "",
      "internal_id": "",
      "mfg": "",
      "mpn": ""
    },
    "layer_pairs": [],
    "layer_presets": [],
    "viewports": []
  },
  "boards": [],
  "cvpcb": {
    "equivalence_files": []
  },
  "erc": {
    "erc_exclusions": [],
    "meta": {
      "version": 0
    },
    "pin_map": [
      [
        0,
        0,
        0,
        0,
        0,
        0,
        1,
        0,
        0,
        0,
        0,
        2
      ],
      [
        0,
        2,
        0,
        1,
        0,
        0,
        1,
        0,
        2,
        2,
        2,
        2
      ],
      [
        0,
        0,
        0,
        0,
        0,
        0,
        1,
        0,
        1,
        0,
        1,
        2
      ],
      [
        0,
        1,
        0,
        0,
        0,
        0,
        1,
        1,
        2,
        1,
        1,
        2
      ],
      [
        0,
        0,
        0,
        0,
        0,
        0,
        1,
        0,
        0,
        0,
        0,
        2
      ],
      [
        0,
        0,
        0,
        0,
        0,
        0,
        0,
        0,
        0,
        0,
        0,
        2
      ],
      [
        1,
        1,
        1,
        1,
        1,
        0,
        1,
        1,
        1,
        1,
        1,
        2
      ],
      [
        0,
        0,
        0,
        1,
        0,
        0,
        1,
        0,
        0,
        0,
        0,
        2
      ],
      [
        0,
        2,
        1,
        2,
        0,
        0,
        1,
        0,
        2,
        2,
        2,
        2
      ],
      [
        0,
        2,
        0,
        1,
        0,
        0,
        1,
        0,
        2,
        0,
        0,
        2
      ],
      [
        0,
        2,
        1,
        1,
        0,
        0,
        1,
        0,
        2,
        0,
        0,
        2
      ],
      [
        2,
        2,
        2,
        2,
        2,
        2,
        2,
        2,
        2,
        2,
        2,
        2
      ]
    ],
    "rule_severities": {
      "bus_definition_conflict": "error",
      "bus_entry_needed": "error",
      "bus_to_bus_conflict": "error",
      "bus_to_net_conflict": "error",
      "conflicting_netclasses": "error",
      "different_unit_footprint": "error",
      "different_unit_net": "error",
      "duplicate_reference": "error",
      "duplicate_sheet_names": "error",
      "endpoint_off_grid": "warning",
      "extra_units": "error",
      "footprint_filter": "ignore",
      "footprint_link_issues": "warning",
      "four_way_junction": "ignore",
      "global_label_dangling": "warning",
      "hier_label_mismatch": "error",
      "label_dangling": "error",
      "label_multiple_wires": "warning",
      "lib_symbol_issues": "warning",
      "lib_symbol_mismatch": "warning",
      "missing_bidi_pin": "warning",
      "missing_input_pin": "warning",
      "missing_power_pin": "error",
      "missing_unit": "warning",
      "multiple_net_names": "warning",
      "net_not_bus_member": "warning",
      "no_connect_connected": "warning",
      "no_connect_dangling": "warning",
      "pin_not_connected": "error",
      "pin_not_driven": "error",
      "pin_to_pin": "warning",
      "power_pin_not_driven": "error",
      "same_local_global_label": "warning",
      "similar_label_and_power": "warning",
      "similar_labels": "warning",
      "similar_power": "warning",
      "simulation_model_issue": "ignore",
      "single_global_label": "ignore",
      "unannotated": "error",
      "unconnected_wire_endpoint": "warning",
      "undefined_netclass": "error",
      "unit_value_mismatch": "error",
      "unresolved_variable": "error",
      "wire_dangling": "error"
    }
  },
  "libraries": {
    "pinned_footprint_libs": [],
    "pinned_symbol_libs": []
  },
  "meta": {
    "filename": "m2-pcie-adapter.kicad_pro",
    "version": 3
  },
  "net_settings": {
    "classes": [
      {
        "bus_width": 12,
        "clearance": 0.145,
        "diff_pair_gap": 0.25,
        "diff_pair_via_gap": 0.25,
        "diff_pair_width": 0.2,
        "line_style": 0,
        "microvia_diameter": 0.3,
        "microvia_drill": 0.1,
        "name": "Default",
        "pcb_color": "rgba(0, 0, 0, 0.000)",
        "priority": 2147483647,
        "schematic_color": "rgba(0, 0, 0, 0.000)",
        "track_width": 0.2,
        "via_diameter": 0.6,
        "via_drill": 0.3,
        "wire_width": 6
      },
      {
        "bus_width": 12,
        "clearance": 0.145,
        "diff_pair_gap": 0.145,
        "diff_pair_via_gap": 0.25,
        "diff_pair_width": 0.185,
        "line_style": 0,
        "microvia_diameter": 0.3,
        "microvia_drill": 0.1,
        "name": "Z85_PCIE",
        "pcb_color": "rgba(0, 0, 0, 0.000)",
        "priority": 0,
        "schematic_color": "rgba(0, 0, 0, 0.000)",
        "track_width": 0.185,
        "via_diameter": 0.6,
        "via_drill": 0.3,
        "wire_width": 6
      }
    ],
    "meta": {
      "version": 4
    },
    "net_colors": null,
    "netclass_assignments": null,
    "netclass_patterns": [
      {
        "netclass": "Default",
        "pattern": ""
      },
      {
        "netclass": "Z85_PCIE",
        "pattern": "*Data_*"
      },
      {
        "netclass": "Z85_PCIE",
        "pattern": "*REFCLK*"
      }
    ]
  },
  "pcbnew": {
    "last_paths": {
      "gencad": "",
      "idf": "",
      "netlist": "",
      "plot": "",
      "pos_files": "",
      "specctra_dsn": "",
      "step": "",
      "svg": "",
      "vrml": ""
    },
    "page_layout_descr_file": ""
  },
  "schematic": {
    "annotate_start_num": 0,
    "bom_export_filename": "${PROJECTNAME}.csv",
    "bom_fmt_presets": [],
    "bom_fmt_settings": {
      "field_delimiter": ",",
      "keep_line_breaks": false,
      "keep_tabs": false,
      "name": "CSV",
      "ref_delimiter": ",",
      "ref_range_delimiter": "",
      "string_delimiter": "\""
    },
    "bom_presets": [],
    "bom_settings": {
      "exclude_dnp": false,
      "fields_ordered": [
        {
          "group_by": false,
          "label": "Reference",
          "name": "Reference",
          "show": true
        },
        {
          "group_by": false,
          "label": "Qty",
          "name": "${QUANTITY}",
          "show": true
        },
        {
          "group_by": true,
          "label": "Value",
          "name": "Value",
          "show": true
        },
        {
          "group_by": true,
          "label": "DNP",
          "name": "${DNP}",
          "show": true
        },
        {
          "group_by": true,
          "label": "Exclude from BOM",
          "name": "${EXCLUDE_FROM_BOM}",
          "show": true
        },
        {
          "group_by": true,
          "label": "Exclude from Board",
          "name": "${EXCLUDE_FROM_BOARD}",
          "show": true
        },
        {
          "group_by": true,
          "label": "Footprint",
          "name": "Footprint",
          "show": true
        },
        {
          "group_by": false,
          "label": "Datasheet",
          "name": "Datasheet",
          "show": true
        }
      ],
      "filter_string": "",
      "group_symbols": true,
      "include_excluded_from_bom": true,
      "name": "Default Editing",
      "sort_asc": true,
      "sort_field": "Reference"
    },
    "connection_grid_size": 50.0,
    "drawing": {
      "dashed_lines_dash_length_ratio": 12.0,
      "dashed_lines_gap_length_ratio": 3.0,
      "default_line_thickness": 6.0,
      "default_text_size": 50.0,
      "field_names": [],
      "intersheets_ref_own_page": false,
      "intersheets_ref_prefix": "",
      "intersheets_ref_short": false,
      "intersheets_ref_show": false,
      "intersheets_ref_suffix": "",
      "junction_size_choice": 3,
      "label_size_ratio": 0.25,
      "operating_point_overlay_i_precision": 3,
      "operating_point_overlay_i_range": "~A",
      "operating_point_overlay_v_precision": 3,
      "operating_point_overlay_v_range": "~V",
      "overbar_offset_ratio": 1.23,
      "pin_symbol_size": 0.0,
      "text_offset_ratio": 0.08
    },
    "legacy_lib_dir": "",
    "legacy_lib_list": [],
    "meta": {
      "version": 1
    },
    "net_format_name": "",
    "page_layout_descr_file": "",
    "plot_directory": "./doc",
    "space_save_all_events": true,
    "spice_adjust_passive_values": false,
    "spice_current_sheet_as_root": false,
    "spice_external_command": "spice \"%I\"",
    "spice_model_current_sheet_as_root": true,
    "spice_save_all_currents": false,
    "spice_save_all_dissipations": false,
    "spice_save_all_voltages": false,
    "subpart_first_id": 65,
    "subpart_id_separator": 0
  },
  "sheets": [
    [
      "",
      "Root"
    ]
  ],
  "text_variables": {}
}
